(kicad_pcb
	(version 20221018)
	(generator pcbnew)
	(general
    (thickness 1.518)
  )
	(paper "A4")
	(title_block
    (title "Kria K26 Devboard")
    (date "2024-03-26")
    (rev "1.2.5")
    (comment 1 "www.antmicro.com")
    (comment 2 "Antmicro Ltd.")
		(comment 9 "footprints 555-564 of 660")
	)
	(layers
    (0 "F.Cu" mixed)
    (1 "In1.Cu" power)
    (2 "In2.Cu" mixed)
    (3 "In3.Cu" power)
    (4 "In4.Cu" mixed)
    (5 "In5.Cu" power)
    (6 "In6.Cu" mixed)
    (31 "B.Cu" power)
    (32 "B.Adhes" user "B.Adhesive")
    (33 "F.Adhes" user "F.Adhesive")
    (34 "B.Paste" user)
    (35 "F.Paste" user)
    (36 "B.SilkS" user "B.Silkscreen")
    (37 "F.SilkS" user "F.Silkscreen")
    (38 "B.Mask" user)
    (39 "F.Mask" user)
    (40 "Dwgs.User" user "User.Drawings")
    (41 "Cmts.User" user "User.Comments")
    (42 "Eco1.User" user "User.Eco1")
    (43 "Eco2.User" user "User.Eco2")
    (44 "Edge.Cuts" user)
    (45 "Margin" user)
    (46 "B.CrtYd" user "B.Courtyard")
    (47 "F.CrtYd" user "F.Courtyard")
    (48 "B.Fab" user)
    (49 "F.Fab" user)
  )
	(footprint "kria-k26-devboard-footprints:C_0402_1005Metric" (layer "B.Cu")
    (at 155.1 86.65)
    (descr "Capacitor SMD 0402")
    (tags "capacitor SMD 0402")
    (property "Author" "Antmicro")
    (property "Dielectric" "X7R")
    (property "License" "Apache-2.0")
    (property "MPN" "GRM155R71H103KA88D")
    (property "Manufacturer" "Murata")
    (property "Sheetfile" "eth.kicad_sch")
    (property "Sheetname" "Ethernet")
    (property "Val" "10n")
    (property "Voltage" "50V")
    (property "ki_description" " ")
    (attr smd)
    (fp_text reference "C92" (at 3.1 0.35 180) (layer "B.SilkS")
        (effects (font (size 0.7 0.7) (thickness 0.15)) (justify left bottom mirror))
    )
    (fp_text value "C_10n_0402" (at 0 -1.4 180) (layer "B.Fab") hide
        (effects (font (size 0.7 0.7) (thickness 0.15)) (justify left bottom mirror))
    )
    (fp_text user "${REFERENCE}" (at -0.932 -3.168 180) (layer "B.Fab") hide
        (effects (font (size 0.7 0.7) (thickness 0.15)) (justify left bottom mirror))
    )
    (fp_text user "License: Apache-2.0" (at -0.932 -5.17 180) (layer "B.Fab") hide
        (effects (font (size 0.7 0.7) (thickness 0.15)) (justify left bottom mirror))
    )
    (fp_text user "Author: Antmicro" (at -0.932 -4.17 180) (layer "B.Fab") hide
        (effects (font (size 0.7 0.7) (thickness 0.15)) (justify left bottom mirror))
    )
    (fp_rect (start -0.94 0.47) (end 0.94 -0.47)
      (stroke (width 0.05) (type solid)) (fill none) (layer "B.CrtYd"))
    (fp_rect (start -0.499 0.249) (end 0.499 -0.249)
      (stroke (width 0.15) (type solid)) (fill none) (layer "B.Fab"))
    (pad "1" smd roundrect (at -0.484 0) (size 0.59 0.64) (layers "B.Cu" "B.Paste" "B.Mask") (roundrect_rratio 0.25)
      (net 17 "PS_1V8") (pintype "passive"))
    (pad "2" smd roundrect (at 0.484 0) (size 0.59 0.64) (layers "B.Cu" "B.Paste" "B.Mask") (roundrect_rratio 0.25)
      (net 1 "GND") (pintype "passive"))
  )
	(footprint "kria-k26-devboard-footprints:C_0402_1005Metric" (layer "B.Cu")
    (at 151.45 85.762385 -90)
    (descr "Capacitor SMD 0402")
    (tags "capacitor SMD 0402")
    (property "Author" "Antmicro")
    (property "Dielectric" "X5R")
    (property "License" "Apache-2.0")
    (property "MPN" "GRM155R61H104KE14D")
    (property "Manufacturer" "Murata")
    (property "Sheetfile" "eth.kicad_sch")
    (property "Sheetname" "Ethernet")
    (property "Val" "100n")
    (property "Voltage" "50V")
    (property "ki_description" " ")
    (attr smd)
    (fp_text reference "C103" (at -3.712385 -0.37 90) (layer "B.SilkS")
        (effects (font (size 0.7 0.7) (thickness 0.15)) (justify left bottom mirror))
    )
    (fp_text value "C_100n_0402" (at 0 -1.4 90) (layer "B.Fab") hide
        (effects (font (size 0.7 0.7) (thickness 0.15)) (justify left bottom mirror))
    )
    (fp_text user "License: Apache-2.0" (at -0.932 -5.17 90) (layer "B.Fab") hide
        (effects (font (size 0.7 0.7) (thickness 0.15)) (justify left bottom mirror))
    )
    (fp_text user "${REFERENCE}" (at -0.932 -3.168 90) (layer "B.Fab") hide
        (effects (font (size 0.7 0.7) (thickness 0.15)) (justify left bottom mirror))
    )
    (fp_text user "Author: Antmicro" (at -0.932 -4.17 90) (layer "B.Fab") hide
        (effects (font (size 0.7 0.7) (thickness 0.15)) (justify left bottom mirror))
    )
    (fp_rect (start -0.94 0.47) (end 0.94 -0.47)
      (stroke (width 0.05) (type solid)) (fill none) (layer "B.CrtYd"))
    (fp_rect (start -0.499 0.249) (end 0.499 -0.249)
      (stroke (width 0.15) (type solid)) (fill none) (layer "B.Fab"))
    (pad "1" smd roundrect (at -0.484 0 270) (size 0.59 0.64) (layers "B.Cu" "B.Paste" "B.Mask") (roundrect_rratio 0.25)
      (net 16 "PS_2V5") (pintype "passive"))
    (pad "2" smd roundrect (at 0.484 0 270) (size 0.59 0.64) (layers "B.Cu" "B.Paste" "B.Mask") (roundrect_rratio 0.25)
      (net 1 "GND") (pintype "passive"))
  )
	(footprint "kria-k26-devboard-footprints:C_0402_1005Metric" (layer "B.Cu")
    (at 146.45 80.625 90)
    (descr "Capacitor SMD 0402")
    (tags "capacitor SMD 0402")
    (property "Author" "Antmicro")
    (property "Dielectric" "X7R")
    (property "License" "Apache-2.0")
    (property "MPN" "GRM155R71H103KA88D")
    (property "Manufacturer" "Murata")
    (property "Sheetfile" "eth.kicad_sch")
    (property "Sheetname" "Ethernet")
    (property "Val" "10n")
    (property "Voltage" "50V")
    (property "ki_description" " ")
    (attr smd)
    (fp_text reference "C93" (at 1.025 2.14 270) (layer "B.SilkS")
        (effects (font (size 0.7 0.7) (thickness 0.15)) (justify left bottom mirror))
    )
    (fp_text value "C_10n_0402" (at 0 -1.4 270) (layer "B.Fab") hide
        (effects (font (size 0.7 0.7) (thickness 0.15)) (justify left bottom mirror))
    )
    (fp_text user "License: Apache-2.0" (at -0.932 -5.17 270) (layer "B.Fab") hide
        (effects (font (size 0.7 0.7) (thickness 0.15)) (justify left bottom mirror))
    )
    (fp_text user "${REFERENCE}" (at -0.932 -3.168 270) (layer "B.Fab") hide
        (effects (font (size 0.7 0.7) (thickness 0.15)) (justify left bottom mirror))
    )
    (fp_text user "Author: Antmicro" (at -0.932 -4.17 270) (layer "B.Fab") hide
        (effects (font (size 0.7 0.7) (thickness 0.15)) (justify left bottom mirror))
    )
    (fp_rect (start -0.94 0.47) (end 0.94 -0.47)
      (stroke (width 0.05) (type solid)) (fill none) (layer "B.CrtYd"))
    (fp_rect (start -0.499 0.249) (end 0.499 -0.249)
      (stroke (width 0.15) (type solid)) (fill none) (layer "B.Fab"))
    (pad "1" smd roundrect (at -0.484 0 90) (size 0.59 0.64) (layers "B.Cu" "B.Paste" "B.Mask") (roundrect_rratio 0.25)
      (net 16 "PS_2V5") (pintype "passive"))
    (pad "2" smd roundrect (at 0.484 0 90) (size 0.59 0.64) (layers "B.Cu" "B.Paste" "B.Mask") (roundrect_rratio 0.25)
      (net 1 "GND") (pintype "passive"))
  )
	(footprint "kria-k26-devboard-footprints:C_0402_1005Metric" (layer "B.Cu")
    (at 145.895911 88.9)
    (descr "Capacitor SMD 0402")
    (tags "capacitor SMD 0402")
    (property "Author" "Antmicro")
    (property "Dielectric" "")
    (property "License" "Apache-2.0")
    (property "MPN" "C1005X6S1A105K050BC")
    (property "Manufacturer" "TDK")
    (property "Sheetfile" "eth.kicad_sch")
    (property "Sheetname" "Ethernet")
    (property "Val" "1u")
    (property "Voltage" "")
    (property "ki_description" " ")
    (attr smd)
    (fp_text reference "C94" (at -0.935911 0.4 180) (layer "B.SilkS")
        (effects (font (size 0.7 0.7) (thickness 0.15)) (justify left bottom mirror))
    )
    (fp_text value "C_1u_0402" (at 0 -1.4 180) (layer "B.Fab") hide
        (effects (font (size 0.7 0.7) (thickness 0.15)) (justify left bottom mirror))
    )
    (fp_text user "${REFERENCE}" (at -0.932 -3.168 180) (layer "B.Fab") hide
        (effects (font (size 0.7 0.7) (thickness 0.15)) (justify left bottom mirror))
    )
    (fp_text user "Author: Antmicro" (at -0.932 -4.17 180) (layer "B.Fab") hide
        (effects (font (size 0.7 0.7) (thickness 0.15)) (justify left bottom mirror))
    )
    (fp_text user "License: Apache-2.0" (at -0.932 -5.17 180) (layer "B.Fab") hide
        (effects (font (size 0.7 0.7) (thickness 0.15)) (justify left bottom mirror))
    )
    (fp_rect (start -0.94 0.47) (end 0.94 -0.47)
      (stroke (width 0.05) (type solid)) (fill none) (layer "B.CrtYd"))
    (fp_rect (start -0.499 0.249) (end 0.499 -0.249)
      (stroke (width 0.15) (type solid)) (fill none) (layer "B.Fab"))
    (pad "1" smd roundrect (at -0.484 0) (size 0.59 0.64) (layers "B.Cu" "B.Paste" "B.Mask") (roundrect_rratio 0.25)
      (net 17 "PS_1V8") (pintype "passive"))
    (pad "2" smd roundrect (at 0.484 0) (size 0.59 0.64) (layers "B.Cu" "B.Paste" "B.Mask") (roundrect_rratio 0.25)
      (net 1 "GND") (pintype "passive"))
  )
	(footprint "kria-k26-devboard-footprints:C_0402_1005Metric" (layer "B.Cu")
    (at 146.45 85.75 -90)
    (descr "Capacitor SMD 0402")
    (tags "capacitor SMD 0402")
    (property "Author" "Antmicro")
    (property "Dielectric" "")
    (property "License" "Apache-2.0")
    (property "MPN" "C1005X6S1A105K050BC")
    (property "Manufacturer" "TDK")
    (property "Sheetfile" "eth.kicad_sch")
    (property "Sheetname" "Ethernet")
    (property "Val" "1u")
    (property "Voltage" "")
    (property "ki_description" " ")
    (attr smd)
    (fp_text reference "C97" (at -3.712385 -0.37 90) (layer "B.SilkS")
        (effects (font (size 0.7 0.7) (thickness 0.15)) (justify left bottom mirror))
    )
    (fp_text value "C_1u_0402" (at 0 -1.4 90) (layer "B.Fab") hide
        (effects (font (size 0.7 0.7) (thickness 0.15)) (justify left bottom mirror))
    )
    (fp_text user "License: Apache-2.0" (at -0.932 -5.17 90) (layer "B.Fab") hide
        (effects (font (size 0.7 0.7) (thickness 0.15)) (justify left bottom mirror))
    )
    (fp_text user "${REFERENCE}" (at -0.932 -3.168 90) (layer "B.Fab") hide
        (effects (font (size 0.7 0.7) (thickness 0.15)) (justify left bottom mirror))
    )
    (fp_text user "Author: Antmicro" (at -0.932 -4.17 90) (layer "B.Fab") hide
        (effects (font (size 0.7 0.7) (thickness 0.15)) (justify left bottom mirror))
    )
    (fp_rect (start -0.94 0.47) (end 0.94 -0.47)
      (stroke (width 0.05) (type solid)) (fill none) (layer "B.CrtYd"))
    (fp_rect (start -0.499 0.249) (end 0.499 -0.249)
      (stroke (width 0.15) (type solid)) (fill none) (layer "B.Fab"))
    (pad "1" smd roundrect (at -0.484 0 270) (size 0.59 0.64) (layers "B.Cu" "B.Paste" "B.Mask") (roundrect_rratio 0.25)
      (net 16 "PS_2V5") (pintype "passive"))
    (pad "2" smd roundrect (at 0.484 0 270) (size 0.59 0.64) (layers "B.Cu" "B.Paste" "B.Mask") (roundrect_rratio 0.25)
      (net 1 "GND") (pintype "passive"))
  )
	(footprint "kria-k26-devboard-footprints:C_0402_1005Metric" (layer "B.Cu")
    (at 151.85 89.8 180)
    (descr "Capacitor SMD 0402")
    (tags "capacitor SMD 0402")
    (property "Author" "Antmicro")
    (property "Dielectric" "")
    (property "License" "Apache-2.0")
    (property "MPN" "C1005X6S1A105K050BC")
    (property "Manufacturer" "TDK")
    (property "Sheetfile" "eth.kicad_sch")
    (property "Sheetname" "Ethernet")
    (property "Val" "1u")
    (property "Voltage" "")
    (property "ki_description" " ")
    (attr smd)
    (fp_text reference "C96" (at 0.87 -0.41) (layer "B.SilkS")
        (effects (font (size 0.7 0.7) (thickness 0.15)) (justify left bottom mirror))
    )
    (fp_text value "C_1u_0402" (at 0 -1.4) (layer "B.Fab") hide
        (effects (font (size 0.7 0.7) (thickness 0.15)) (justify left bottom mirror))
    )
    (fp_text user "License: Apache-2.0" (at -0.932 -5.17) (layer "B.Fab") hide
        (effects (font (size 0.7 0.7) (thickness 0.15)) (justify left bottom mirror))
    )
    (fp_text user "Author: Antmicro" (at -0.932 -4.17) (layer "B.Fab") hide
        (effects (font (size 0.7 0.7) (thickness 0.15)) (justify left bottom mirror))
    )
    (fp_text user "${REFERENCE}" (at -0.932 -3.168) (layer "B.Fab") hide
        (effects (font (size 0.7 0.7) (thickness 0.15)) (justify left bottom mirror))
    )
    (fp_rect (start -0.94 0.47) (end 0.94 -0.47)
      (stroke (width 0.05) (type solid)) (fill none) (layer "B.CrtYd"))
    (fp_rect (start -0.499 0.249) (end 0.499 -0.249)
      (stroke (width 0.15) (type solid)) (fill none) (layer "B.Fab"))
    (pad "1" smd roundrect (at -0.484 0 180) (size 0.59 0.64) (layers "B.Cu" "B.Paste" "B.Mask") (roundrect_rratio 0.25)
      (net 17 "PS_1V8") (pintype "passive"))
    (pad "2" smd roundrect (at 0.484 0 180) (size 0.59 0.64) (layers "B.Cu" "B.Paste" "B.Mask") (roundrect_rratio 0.25)
      (net 1 "GND") (pintype "passive"))
  )
	(footprint "kria-k26-devboard-footprints:C_0402_1005Metric" (layer "B.Cu")
    (at 148.3 91.614035 90)
    (descr "Capacitor SMD 0402")
    (tags "capacitor SMD 0402")
    (property "Author" "Antmicro")
    (property "Dielectric" "")
    (property "License" "Apache-2.0")
    (property "MPN" "C1005X6S1A105K050BC")
    (property "Manufacturer" "TDK")
    (property "Sheetfile" "eth.kicad_sch")
    (property "Sheetname" "Ethernet")
    (property "Val" "1u")
    (property "Voltage" "")
    (property "ki_description" " ")
    (attr smd)
    (fp_text reference "C95" (at -0.895965 0.42 270) (layer "B.SilkS")
        (effects (font (size 0.7 0.7) (thickness 0.15)) (justify left bottom mirror))
    )
    (fp_text value "C_1u_0402" (at 0 -1.4 270) (layer "B.Fab") hide
        (effects (font (size 0.7 0.7) (thickness 0.15)) (justify left bottom mirror))
    )
    (fp_text user "${REFERENCE}" (at -0.932 -3.168 270) (layer "B.Fab") hide
        (effects (font (size 0.7 0.7) (thickness 0.15)) (justify left bottom mirror))
    )
    (fp_text user "License: Apache-2.0" (at -0.932 -5.17 270) (layer "B.Fab") hide
        (effects (font (size 0.7 0.7) (thickness 0.15)) (justify left bottom mirror))
    )
    (fp_text user "Author: Antmicro" (at -0.932 -4.17 270) (layer "B.Fab") hide
        (effects (font (size 0.7 0.7) (thickness 0.15)) (justify left bottom mirror))
    )
    (fp_rect (start -0.94 0.47) (end 0.94 -0.47)
      (stroke (width 0.05) (type solid)) (fill none) (layer "B.CrtYd"))
    (fp_rect (start -0.499 0.249) (end 0.499 -0.249)
      (stroke (width 0.15) (type solid)) (fill none) (layer "B.Fab"))
    (pad "1" smd roundrect (at -0.484 0 90) (size 0.59 0.64) (layers "B.Cu" "B.Paste" "B.Mask") (roundrect_rratio 0.25)
      (net 17 "PS_1V8") (pintype "passive"))
    (pad "2" smd roundrect (at 0.484 0 90) (size 0.59 0.64) (layers "B.Cu" "B.Paste" "B.Mask") (roundrect_rratio 0.25)
      (net 1 "GND") (pintype "passive"))
  )
	(footprint "kria-k26-devboard-footprints:R_0402_1005Metric" (layer "B.Cu")
    (at 154.629289 92.675)
    (descr "Resistor SMD 0402")
    (tags "resistor SMD 0402")
    (property "Author" "Antmicro")
    (property "License" "Apache-2.0")
    (property "MPN" "CR0402-FX-2491GLF")
    (property "Manufacturer" "Bourns")
    (property "Sheetfile" "eth.kicad_sch")
    (property "Sheetname" "Ethernet")
    (property "Tolerance" "1%")
    (property "Val" "2k49")
    (property "ki_description" "2k49 resistor in 0402 package with 1% tolerance")
    (attr smd)
    (fp_text reference "R70" (at 3.000711 0.405 180) (layer "B.SilkS")
        (effects (font (size 0.7 0.7) (thickness 0.15)) (justify left bottom mirror))
    )
    (fp_text value "R_2k49_0402" (at 0 -1.4 180) (layer "B.Fab") hide
        (effects (font (size 0.7 0.7) (thickness 0.15)) (justify left bottom mirror))
    )
    (fp_text user "${REFERENCE}" (at -0.95 -3.168 180) (layer "B.Fab") hide
        (effects (font (size 0.7 0.7) (thickness 0.15)) (justify left bottom mirror))
    )
    (fp_text user "License: Apache-2.0" (at -0.95 -5.169 180) (layer "B.Fab") hide
        (effects (font (size 0.7 0.7) (thickness 0.15)) (justify left bottom mirror))
    )
    (fp_text user "Author: Antmicro" (at -0.95 -4.169 180) (layer "B.Fab") hide
        (effects (font (size 0.7 0.7) (thickness 0.15)) (justify left bottom mirror))
    )
    (fp_rect (start -0.93 0.47) (end 0.93 -0.47)
      (stroke (width 0.05) (type solid)) (fill none) (layer "B.CrtYd"))
    (fp_rect (start -0.5 0.25) (end 0.5 -0.25)
      (stroke (width 0.15) (type solid)) (fill none) (layer "B.Fab"))
    (pad "1" smd roundrect (at -0.485 0) (size 0.59 0.64) (layers "B.Cu" "B.Paste" "B.Mask") (roundrect_rratio 0.25)
      (net 28 "/Ethernet/MIO75") (pintype "passive"))
    (pad "2" smd roundrect (at 0.485 0) (size 0.59 0.64) (layers "B.Cu" "B.Paste" "B.Mask") (roundrect_rratio 0.25)
      (net 1 "GND") (pintype "passive"))
  )
	(footprint "kria-k26-devboard-footprints:C_0402_1005Metric" (layer "B.Cu")
    (at 145.94591 91.514035)
    (descr "Capacitor SMD 0402")
    (tags "capacitor SMD 0402")
    (property "Author" "Antmicro")
    (property "Dielectric" "")
    (property "License" "Apache-2.0")
    (property "MPN" "C1005X6S1A105K050BC")
    (property "Manufacturer" "TDK")
    (property "Sheetfile" "eth.kicad_sch")
    (property "Sheetname" "Ethernet")
    (property "Val" "1u")
    (property "Voltage" "")
    (property "ki_description" " ")
    (attr smd)
    (fp_text reference "C110" (at 1.40409 1.355965 180) (layer "B.SilkS")
        (effects (font (size 0.7 0.7) (thickness 0.15)) (justify left bottom mirror))
    )
    (fp_text value "C_1u_0402" (at 0 -1.4 180) (layer "B.Fab") hide
        (effects (font (size 0.7 0.7) (thickness 0.15)) (justify left bottom mirror))
    )
    (fp_text user "${REFERENCE}" (at -0.932 -3.168 180) (layer "B.Fab") hide
        (effects (font (size 0.7 0.7) (thickness 0.15)) (justify left bottom mirror))
    )
    (fp_text user "License: Apache-2.0" (at -0.932 -5.17 180) (layer "B.Fab") hide
        (effects (font (size 0.7 0.7) (thickness 0.15)) (justify left bottom mirror))
    )
    (fp_text user "Author: Antmicro" (at -0.932 -4.17 180) (layer "B.Fab") hide
        (effects (font (size 0.7 0.7) (thickness 0.15)) (justify left bottom mirror))
    )
    (fp_rect (start -0.94 0.47) (end 0.94 -0.47)
      (stroke (width 0.05) (type solid)) (fill none) (layer "B.CrtYd"))
    (fp_rect (start -0.499 0.249) (end 0.499 -0.249)
      (stroke (width 0.15) (type solid)) (fill none) (layer "B.Fab"))
    (pad "1" smd roundrect (at -0.484 0) (size 0.59 0.64) (layers "B.Cu" "B.Paste" "B.Mask") (roundrect_rratio 0.25)
      (net 19 "PS_1V0") (pintype "passive"))
    (pad "2" smd roundrect (at 0.484 0) (size 0.59 0.64) (layers "B.Cu" "B.Paste" "B.Mask") (roundrect_rratio 0.25)
      (net 1 "GND") (pintype "passive"))
  )
	(footprint "kria-k26-devboard-footprints:C_0402_1005Metric" (layer "B.Cu")
    (at 150.45 85.762385 -90)
    (descr "Capacitor SMD 0402")
    (tags "capacitor SMD 0402")
    (property "Author" "Antmicro")
    (property "Dielectric" "")
    (property "License" "Apache-2.0")
    (property "MPN" "C1005X6S1A105K050BC")
    (property "Manufacturer" "TDK")
    (property "Sheetfile" "eth.kicad_sch")
    (property "Sheetname" "Ethernet")
    (property "Val" "1u")
    (property "Voltage" "")
    (property "ki_description" " ")
    (attr smd)
    (fp_text reference "C98" (at -3.712385 -0.37 90) (layer "B.SilkS")
        (effects (font (size 0.7 0.7) (thickness 0.15)) (justify left bottom mirror))
    )
    (fp_text value "C_1u_0402" (at 0 -1.4 90) (layer "B.Fab") hide
        (effects (font (size 0.7 0.7) (thickness 0.15)) (justify left bottom mirror))
    )
    (fp_text user "${REFERENCE}" (at -0.932 -3.168 90) (layer "B.Fab") hide
        (effects (font (size 0.7 0.7) (thickness 0.15)) (justify left bottom mirror))
    )
    (fp_text user "License: Apache-2.0" (at -0.932 -5.17 90) (layer "B.Fab") hide
        (effects (font (size 0.7 0.7) (thickness 0.15)) (justify left bottom mirror))
    )
    (fp_text user "Author: Antmicro" (at -0.932 -4.17 90) (layer "B.Fab") hide
        (effects (font (size 0.7 0.7) (thickness 0.15)) (justify left bottom mirror))
    )
    (fp_rect (start -0.94 0.47) (end 0.94 -0.47)
      (stroke (width 0.05) (type solid)) (fill none) (layer "B.CrtYd"))
    (fp_rect (start -0.499 0.249) (end 0.499 -0.249)
      (stroke (width 0.15) (type solid)) (fill none) (layer "B.Fab"))
    (pad "1" smd roundrect (at -0.484 0 270) (size 0.59 0.64) (layers "B.Cu" "B.Paste" "B.Mask") (roundrect_rratio 0.25)
      (net 16 "PS_2V5") (pintype "passive"))
    (pad "2" smd roundrect (at 0.484 0 270) (size 0.59 0.64) (layers "B.Cu" "B.Paste" "B.Mask") (roundrect_rratio 0.25)
      (net 1 "GND") (pintype "passive"))
  )
)
